# S9S_MB_2U (Grand Teton) — schematic netlist excerpt (pin names and nets, part order shuffled) for the footprints in the layout excerpt that follows; sources: Cadence DE-HDL packaged netlist, KiCad conversion of 03242023_DA0F0TMBIJ0_F0T_Motherboard_J_brd_V01_OCP.brd

PC325  Q_CAPP  560UF 2.5V 20% OSCON  pkg THLF  page 267 : A = PVCCIN_CPU0 ; B = GND
R2240  Q_RES  10K 1% EMPTY  pkg 0402LF  page 195 : A = P1V05_PCH_AUX ; B = FM_BOARD_SKU_ID1
R4727  Q_RES  10K 1% CHIP  pkg 0402LF  page 144 : A = P3V3_AUX ; B = PRSNT_SWB_N

(kicad_pcb
	(version 20260206)
	(generator "pcbnew")
	(generator_version "10.0")
	(general
		(thickness 1.6)
		(legacy_teardrops no)
	)
	(paper "A4")
	(title_block
		(title "03242023_DA0F0TMBIJ0_F0T_Motherboard_J_brd_V01_OCP.brd")
		(comment 1 "Grand Teton / footprints 3928-3930 of 6105")
	)
	(layers
		(0 "F.Cu" signal "TOP")
		(4 "In1.Cu" signal "GND")
		(6 "In2.Cu" signal "IN1")
		(8 "In3.Cu" signal "GND1")
		(10 "In4.Cu" signal "IN2")
		(12 "In5.Cu" signal "GND2")
		(14 "In6.Cu" signal "IN3")
		(16 "In7.Cu" signal "GND3")
		(18 "In8.Cu" signal "VCC")
		(20 "In9.Cu" signal "VCC1")
		(22 "In10.Cu" signal "GND4")
		(24 "In11.Cu" signal "IN4")
		(26 "In12.Cu" signal "GND5")
		(28 "In13.Cu" signal "IN5")
		(30 "In14.Cu" signal "GND6")
		(32 "In15.Cu" signal "IN6")
		(34 "In16.Cu" signal "GND7")
		(2 "B.Cu" signal "BOTTOM")
		(9 "F.Adhes" user "F.Adhesive")
		(11 "B.Adhes" user "B.Adhesive")
		(13 "F.Paste" user "Package Geometry/Pastemask Top")
		(15 "B.Paste" user "Package Geometry/Pastemask Bottom")
		(5 "F.SilkS" user "Ref Des/Silkscreen Top")
		(7 "B.SilkS" user "Ref Des/Silkscreen Bottom")
		(1 "F.Mask" user "Board Geometry/Soldermask Top")
		(3 "B.Mask" user "Board Geometry/Soldermask Bottom")
		(17 "Dwgs.User" user "User.Drawings")
		(19 "Cmts.User" user "User.Comments")
		(21 "Eco1.User" user "User.Eco1")
		(23 "Eco2.User" user "User.Eco2")
		(25 "Edge.Cuts" user "Board Geometry/Outline")
		(27 "Margin" user)
		(31 "F.CrtYd" user "Package Geometry/Place Bound Top")
		(29 "B.CrtYd" user "Package Geometry/Place Bound Bottom")
		(35 "F.Fab" user "Ref Des/Assembly Top")
		(33 "B.Fab" user "Ref Des/Assembly Bottom")
	)
	(footprint ""
		(layer "F.Cu")
		(at 299.02023 -50.336196)
		(property "Reference" "R2240"
			(at 0 0 0)
			(layer "F.SilkS")
			(hide yes)
			(effects
				(font
					(size 1.27 1.27)
				)
			)
		)
		(property "Value" ""
			(at 0 0 0)
			(layer "F.Fab")
			(effects
				(font
					(size 1.27 1.27)
				)
			)
		)
		(duplicate_pad_numbers_are_jumpers no)
		(fp_line
			(start -0.7874 -0.4064)
			(end 0.7874 -0.4064)
			(stroke
				(width 0.1524)
				(type default)
			)
			(layer "F.SilkS")
		)
		(fp_line
			(start -0.7874 0.4064)
			(end -0.7874 -0.4064)
			(stroke
				(width 0.1524)
				(type default)
			)
			(layer "F.SilkS")
		)
		(fp_line
			(start 0.7874 -0.4064)
			(end 0.7874 0.4064)
			(stroke
				(width 0.1524)
				(type default)
			)
			(layer "F.SilkS")
		)
		(fp_line
			(start 0.7874 0.4064)
			(end -0.7874 0.4064)
			(stroke
				(width 0.1524)
				(type default)
			)
			(layer "F.SilkS")
		)
		(fp_line
			(start -0.67945 -0.305054)
			(end -0.12065 -0.305054)
			(stroke
				(width 0.1)
				(type default)
			)
			(layer "F.Fab")
		)
		(fp_line
			(start -0.67945 0.3048)
			(end -0.67945 -0.305054)
			(stroke
				(width 0.1)
				(type default)
			)
			(layer "F.Fab")
		)
		(fp_line
			(start -0.12065 -0.305054)
			(end -0.12065 -0.2794)
			(stroke
				(width 0.1)
				(type default)
			)
			(layer "F.Fab")
		)
		(fp_line
			(start -0.12065 -0.2794)
			(end 0.12065 -0.2794)
			(stroke
				(width 0.1)
				(type default)
			)
			(layer "F.Fab")
		)
		(fp_line
			(start -0.12065 0.2794)
			(end -0.12065 0.3048)
			(stroke
				(width 0.1)
				(type default)
			)
			(layer "F.Fab")
		)
		(fp_line
			(start -0.12065 0.3048)
			(end -0.67945 0.3048)
			(stroke
				(width 0.1)
				(type default)
			)
			(layer "F.Fab")
		)
		(fp_line
			(start 0.120396 0.2794)
			(end -0.12065 0.2794)
			(stroke
				(width 0.1)
				(type default)
			)
			(layer "F.Fab")
		)
		(fp_line
			(start 0.120396 0.3048)
			(end 0.120396 0.2794)
			(stroke
				(width 0.1)
				(type default)
			)
			(layer "F.Fab")
		)
		(fp_line
			(start 0.12065 -0.3048)
			(end 0.67945 -0.3048)
			(stroke
				(width 0.1)
				(type default)
			)
			(layer "F.Fab")
		)
		(fp_line
			(start 0.12065 -0.2794)
			(end 0.12065 -0.3048)
			(stroke
				(width 0.1)
				(type default)
			)
			(layer "F.Fab")
		)
		(fp_line
			(start 0.67945 -0.3048)
			(end 0.67945 0.3048)
			(stroke
				(width 0.1)
				(type default)
			)
			(layer "F.Fab")
		)
		(fp_line
			(start 0.67945 0.3048)
			(end 0.120396 0.3048)
			(stroke
				(width 0.1)
				(type default)
			)
			(layer "F.Fab")
		)
		(pad "1" smd circle
			(at -0.40005 0)
			(size 0 0)
			(layers "F.Cu" "F.Mask" "F.Paste")
			(net "P1V05_PCH_AUX")
		)
		(pad "2" smd circle
			(at 0.40005 0)
			(size 0 0)
			(layers "F.Cu" "F.Mask" "F.Paste")
			(net "FM_BOARD_SKU_ID1")
		)
	)
	(footprint ""
		(layer "F.Cu")
		(at 346.465652 -315.66739 90)
		(property "Reference" "PC325"
			(at 0 0 90)
			(layer "F.SilkS")
			(hide yes)
			(effects
				(font
					(size 1.27 1.27)
				)
			)
		)
		(property "Value" ""
			(at 0 0 90)
			(layer "F.Fab")
			(effects
				(font
					(size 1.27 1.27)
				)
			)
		)
		(duplicate_pad_numbers_are_jumpers no)
		(fp_line
			(start 2.750058 0.999998)
			(end -2.750058 0.999998)
			(stroke
				(width 0.1524)
				(type default)
			)
			(layer "F.SilkS")
		)
		(fp_circle
			(center 0 0.999998)
			(end 0 3.750056)
			(stroke
				(width 0.1524)
				(type default)
			)
			(fill no)
			(layer "F.SilkS")
		)
		(fp_poly
			(pts
				(arc
					(start 2.750058 0.999998)
					(mid 0 3.750056)
					(end -2.750058 0.999998)
				)
			)
			(stroke
				(width 0)
				(type default)
			)
			(fill yes)
			(layer "F.SilkS")
		)
		(fp_circle
			(center 0 0.999998)
			(end 0 3.750056)
			(stroke
				(width 0.1)
				(type default)
			)
			(fill no)
			(layer "F.Fab")
		)
		(pad "1" thru_hole rect
			(at 0 0 90)
			(size 1.5748 1.5748)
			(drill 1.0668)
			(layers "*.Cu" "*.Mask")
			(remove_unused_layers no)
			(net "PVCCIN_CPU0")
			(clearance 0)
			(padstack
				(mode front_inner_back)
				(layer "Inner"
					(shape circle)
					(size 1.5748 1.5748)
					(clearance 0)
				)
				(layer "B.Cu"
					(shape rect)
					(size 1.5748 1.5748)
					(clearance 0)
				)
			)
		)
		(pad "2" thru_hole circle
			(at 0 1.999996 90)
			(size 1.5748 1.5748)
			(drill 1.0668)
			(layers "*.Cu" "*.Mask")
			(remove_unused_layers no)
			(net "GND")
			(clearance 0)
		)
	)
	(footprint ""
		(layer "F.Cu")
		(at 104.8258 -409.2702)
		(property "Reference" "R4727"
			(at 0 0 0)
			(layer "F.SilkS")
			(hide yes)
			(effects
				(font
					(size 1.27 1.27)
				)
			)
		)
		(property "Value" ""
			(at 0 0 0)
			(layer "F.Fab")
			(effects
				(font
					(size 1.27 1.27)
				)
			)
		)
		(duplicate_pad_numbers_are_jumpers no)
		(fp_line
			(start -0.7874 -0.4064)
			(end 0.7874 -0.4064)
			(stroke
				(width 0.1524)
				(type default)
			)
			(layer "F.SilkS")
		)
		(fp_line
			(start -0.7874 0.4064)
			(end -0.7874 -0.4064)
			(stroke
				(width 0.1524)
				(type default)
			)
			(layer "F.SilkS")
		)
		(fp_line
			(start 0.7874 -0.4064)
			(end 0.7874 0.4064)
			(stroke
				(width 0.1524)
				(type default)
			)
			(layer "F.SilkS")
		)
		(fp_line
			(start 0.7874 0.4064)
			(end -0.7874 0.4064)
			(stroke
				(width 0.1524)
				(type default)
			)
			(layer "F.SilkS")
		)
		(fp_line
			(start -0.67945 -0.305054)
			(end -0.12065 -0.305054)
			(stroke
				(width 0.1)
				(type default)
			)
			(layer "F.Fab")
		)
		(fp_line
			(start -0.67945 0.3048)
			(end -0.67945 -0.305054)
			(stroke
				(width 0.1)
				(type default)
			)
			(layer "F.Fab")
		)
		(fp_line
			(start -0.12065 -0.305054)
			(end -0.12065 -0.2794)
			(stroke
				(width 0.1)
				(type default)
			)
			(layer "F.Fab")
		)
		(fp_line
			(start -0.12065 -0.2794)
			(end 0.12065 -0.2794)
			(stroke
				(width 0.1)
				(type default)
			)
			(layer "F.Fab")
		)
		(fp_line
			(start -0.12065 0.2794)
			(end -0.12065 0.3048)
			(stroke
				(width 0.1)
				(type default)
			)
			(layer "F.Fab")
		)
		(fp_line
			(start -0.12065 0.3048)
			(end -0.67945 0.3048)
			(stroke
				(width 0.1)
				(type default)
			)
			(layer "F.Fab")
		)
		(fp_line
			(start 0.120396 0.2794)
			(end -0.12065 0.2794)
			(stroke
				(width 0.1)
				(type default)
			)
			(layer "F.Fab")
		)
		(fp_line
			(start 0.120396 0.3048)
			(end 0.120396 0.2794)
			(stroke
				(width 0.1)
				(type default)
			)
			(layer "F.Fab")
		)
		(fp_line
			(start 0.12065 -0.3048)
			(end 0.67945 -0.3048)
			(stroke
				(width 0.1)
				(type default)
			)
			(layer "F.Fab")
		)
		(fp_line
			(start 0.12065 -0.2794)
			(end 0.12065 -0.3048)
			(stroke
				(width 0.1)
				(type default)
			)
			(layer "F.Fab")
		)
		(fp_line
			(start 0.67945 -0.3048)
			(end 0.67945 0.3048)
			(stroke
				(width 0.1)
				(type default)
			)
			(layer "F.Fab")
		)
		(fp_line
			(start 0.67945 0.3048)
			(end 0.120396 0.3048)
			(stroke
				(width 0.1)
				(type default)
			)
			(layer "F.Fab")
		)
		(pad "1" smd circle
			(at -0.40005 0)
			(size 0 0)
			(layers "F.Cu" "F.Mask" "F.Paste")
			(net "P3V3_AUX")
		)
		(pad "2" smd circle
			(at 0.40005 0)
			(size 0 0)
			(layers "F.Cu" "F.Mask" "F.Paste")
			(net "PRSNT_SWB_N")
		)
	)
)
